(kicad_pcb
	(version 20260206)
	(generator "pcbnew")
	(generator_version "10.0")
	(general
		(thickness 1.6)
		(legacy_teardrops no)
	)
	(paper "A4")
	(title_block
		(title "04192023_DAF0TMB3IC0_F0TG_MB_C_brd_V02_OCP.brd")
		(comment 1 "Grand Teton / footprints 5451-5458 of 8354")
	)
	(layers
		(0 "F.Cu" signal "TOP")
		(4 "In1.Cu" signal "GND")
		(6 "In2.Cu" signal "IN1")
		(8 "In3.Cu" signal "GND1")
		(10 "In4.Cu" signal "IN2")
		(12 "In5.Cu" signal "GND2")
		(14 "In6.Cu" signal "IN3")
		(16 "In7.Cu" signal "GND3")
		(18 "In8.Cu" signal "VCC")
		(20 "In9.Cu" signal "VCC1")
		(22 "In10.Cu" signal "GND4")
		(24 "In11.Cu" signal "IN4")
		(26 "In12.Cu" signal "GND5")
		(28 "In13.Cu" signal "IN5")
		(30 "In14.Cu" signal "GND6")
		(32 "In15.Cu" signal "IN6")
		(34 "In16.Cu" signal "GND7")
		(2 "B.Cu" signal "BOTTOM")
		(9 "F.Adhes" user "F.Adhesive")
		(11 "B.Adhes" user "B.Adhesive")
		(13 "F.Paste" user "Package Geometry/Pastemask Top")
		(15 "B.Paste" user "Package Geometry/Pastemask Bottom")
		(5 "F.SilkS" user "Ref Des/Silkscreen Top")
		(7 "B.SilkS" user "Ref Des/Silkscreen Bottom")
		(1 "F.Mask" user "Board Geometry/Soldermask Top")
		(3 "B.Mask" user "Board Geometry/Soldermask Bottom")
		(17 "Dwgs.User" user "User.Drawings")
		(19 "Cmts.User" user "User.Comments")
		(21 "Eco1.User" user "User.Eco1")
		(23 "Eco2.User" user "User.Eco2")
		(25 "Edge.Cuts" user "Board Geometry/Outline")
		(27 "Margin" user)
		(31 "F.CrtYd" user "Package Geometry/Place Bound Top")
		(29 "B.CrtYd" user "Package Geometry/Place Bound Bottom")
		(35 "F.Fab" user "Ref Des/Assembly Top")
		(33 "B.Fab" user "Ref Des/Assembly Bottom")
	)
	(footprint ""
		(layer "B.Cu")
		(at 239.141 -330.581)
		(property "Reference" "R847"
			(at 0 0 0)
			(layer "B.SilkS")
			(hide yes)
			(effects
				(font
					(size 1.27 1.27)
				)
				(justify mirror)
			)
		)
		(property "Value" ""
			(at 0 0 0)
			(layer "B.Fab")
			(effects
				(font
					(size 1.27 1.27)
				)
				(justify mirror)
			)
		)
		(duplicate_pad_numbers_are_jumpers no)
		(fp_line
			(start -0.32512 -0.175006)
			(end -0.32512 0.175006)
			(stroke
				(width 0.1)
				(type default)
			)
			(layer "B.Fab")
		)
		(fp_line
			(start -0.32512 0.175006)
			(end 0.32512 0.175006)
			(stroke
				(width 0.1)
				(type default)
			)
			(layer "B.Fab")
		)
		(fp_line
			(start 0.32512 -0.175006)
			(end -0.32512 -0.175006)
			(stroke
				(width 0.1)
				(type default)
			)
			(layer "B.Fab")
		)
		(fp_line
			(start 0.32512 0.175006)
			(end 0.32512 -0.175006)
			(stroke
				(width 0.1)
				(type default)
			)
			(layer "B.Fab")
		)
		(pad "1" smd rect
			(at 0.2667 0 180)
			(size 0.3048 0.381)
			(layers "B.Cu" "B.Mask" "B.Paste")
			(net "RT_ROM_SMB_MUX_ADDR0")
		)
		(pad "2" smd rect
			(at -0.2667 0)
			(size 0.3048 0.381)
			(layers "B.Cu" "B.Mask" "B.Paste")
			(net "GND")
		)
	)
	(footprint ""
		(layer "B.Cu")
		(at 370.376958 -272.284952)
		(property "Reference" "C2215"
			(at 0 0 0)
			(layer "B.SilkS")
			(hide yes)
			(effects
				(font
					(size 1.27 1.27)
				)
				(justify mirror)
			)
		)
		(property "Value" ""
			(at 0 0 0)
			(layer "B.Fab")
			(effects
				(font
					(size 1.27 1.27)
				)
				(justify mirror)
			)
		)
		(duplicate_pad_numbers_are_jumpers no)
		(fp_line
			(start -0.7874 -0.4064)
			(end -0.7874 0.4064)
			(stroke
				(width 0.1524)
				(type default)
			)
			(layer "B.SilkS")
		)
		(fp_line
			(start -0.7874 0.4064)
			(end 0.7874 0.4064)
			(stroke
				(width 0.1524)
				(type default)
			)
			(layer "B.SilkS")
		)
		(fp_line
			(start 0.7874 -0.4064)
			(end -0.7874 -0.4064)
			(stroke
				(width 0.1524)
				(type default)
			)
			(layer "B.SilkS")
		)
		(fp_line
			(start 0.7874 0.4064)
			(end 0.7874 -0.4064)
			(stroke
				(width 0.1524)
				(type default)
			)
			(layer "B.SilkS")
		)
		(fp_line
			(start -0.67945 -0.3048)
			(end -0.67945 0.3048)
			(stroke
				(width 0.1)
				(type default)
			)
			(layer "B.Fab")
		)
		(fp_line
			(start -0.67945 0.3048)
			(end -0.120396 0.3048)
			(stroke
				(width 0.1)
				(type default)
			)
			(layer "B.Fab")
		)
		(fp_line
			(start -0.12065 -0.3048)
			(end -0.67945 -0.3048)
			(stroke
				(width 0.1)
				(type default)
			)
			(layer "B.Fab")
		)
		(fp_line
			(start -0.12065 -0.2794)
			(end -0.12065 -0.3048)
			(stroke
				(width 0.1)
				(type default)
			)
			(layer "B.Fab")
		)
		(fp_line
			(start -0.120396 0.2794)
			(end 0.12065 0.2794)
			(stroke
				(width 0.1)
				(type default)
			)
			(layer "B.Fab")
		)
		(fp_line
			(start -0.120396 0.3048)
			(end -0.120396 0.2794)
			(stroke
				(width 0.1)
				(type default)
			)
			(layer "B.Fab")
		)
		(fp_line
			(start 0.12065 -0.305054)
			(end 0.12065 -0.2794)
			(stroke
				(width 0.1)
				(type default)
			)
			(layer "B.Fab")
		)
		(fp_line
			(start 0.12065 -0.2794)
			(end -0.12065 -0.2794)
			(stroke
				(width 0.1)
				(type default)
			)
			(layer "B.Fab")
		)
		(fp_line
			(start 0.12065 0.2794)
			(end 0.12065 0.3048)
			(stroke
				(width 0.1)
				(type default)
			)
			(layer "B.Fab")
		)
		(fp_line
			(start 0.12065 0.3048)
			(end 0.67945 0.3048)
			(stroke
				(width 0.1)
				(type default)
			)
			(layer "B.Fab")
		)
		(fp_line
			(start 0.67945 -0.305054)
			(end 0.12065 -0.305054)
			(stroke
				(width 0.1)
				(type default)
			)
			(layer "B.Fab")
		)
		(fp_line
			(start 0.67945 0.3048)
			(end 0.67945 -0.305054)
			(stroke
				(width 0.1)
				(type default)
			)
			(layer "B.Fab")
		)
		(pad "1" smd circle
			(at 0.40005 0 180)
			(size 0 0)
			(layers "B.Cu" "B.Mask" "B.Paste")
			(net "PVDDCR_CPU1_P0")
		)
		(pad "2" smd circle
			(at -0.40005 0 180)
			(size 0 0)
			(layers "B.Cu" "B.Mask" "B.Paste")
			(net "GND")
		)
	)
	(footprint ""
		(layer "B.Cu")
		(at 315.585094 -40.33774 -90)
		(property "Reference" "R3941"
			(at 0 0 90)
			(layer "B.SilkS")
			(hide yes)
			(effects
				(font
					(size 1.27 1.27)
				)
				(justify mirror)
			)
		)
		(property "Value" ""
			(at 0 0 90)
			(layer "B.Fab")
			(effects
				(font
					(size 1.27 1.27)
				)
				(justify mirror)
			)
		)
		(duplicate_pad_numbers_are_jumpers no)
		(fp_line
			(start -0.7874 0.4064)
			(end 0.7874 0.4064)
			(stroke
				(width 0.1524)
				(type default)
			)
			(layer "B.SilkS")
		)
		(fp_line
			(start 0.7874 0.4064)
			(end 0.7874 -0.4064)
			(stroke
				(width 0.1524)
				(type default)
			)
			(layer "B.SilkS")
		)
		(fp_line
			(start -0.7874 -0.4064)
			(end -0.7874 0.4064)
			(stroke
				(width 0.1524)
				(type default)
			)
			(layer "B.SilkS")
		)
		(fp_line
			(start 0.7874 -0.4064)
			(end -0.7874 -0.4064)
			(stroke
				(width 0.1524)
				(type default)
			)
			(layer "B.SilkS")
		)
		(fp_line
			(start -0.67945 0.3048)
			(end -0.120396 0.3048)
			(stroke
				(width 0.1)
				(type default)
			)
			(layer "B.Fab")
		)
		(fp_line
			(start -0.120396 0.3048)
			(end -0.120396 0.2794)
			(stroke
				(width 0.1)
				(type default)
			)
			(layer "B.Fab")
		)
		(fp_line
			(start 0.12065 0.3048)
			(end 0.67945 0.3048)
			(stroke
				(width 0.1)
				(type default)
			)
			(layer "B.Fab")
		)
		(fp_line
			(start 0.67945 0.3048)
			(end 0.67945 -0.305054)
			(stroke
				(width 0.1)
				(type default)
			)
			(layer "B.Fab")
		)
		(fp_line
			(start -0.120396 0.2794)
			(end 0.12065 0.2794)
			(stroke
				(width 0.1)
				(type default)
			)
			(layer "B.Fab")
		)
		(fp_line
			(start 0.12065 0.2794)
			(end 0.12065 0.3048)
			(stroke
				(width 0.1)
				(type default)
			)
			(layer "B.Fab")
		)
		(fp_line
			(start -0.12065 -0.2794)
			(end -0.12065 -0.3048)
			(stroke
				(width 0.1)
				(type default)
			)
			(layer "B.Fab")
		)
		(fp_line
			(start 0.12065 -0.2794)
			(end -0.12065 -0.2794)
			(stroke
				(width 0.1)
				(type default)
			)
			(layer "B.Fab")
		)
		(fp_line
			(start -0.67945 -0.3048)
			(end -0.67945 0.3048)
			(stroke
				(width 0.1)
				(type default)
			)
			(layer "B.Fab")
		)
		(fp_line
			(start -0.12065 -0.3048)
			(end -0.67945 -0.3048)
			(stroke
				(width 0.1)
				(type default)
			)
			(layer "B.Fab")
		)
		(fp_line
			(start 0.12065 -0.305054)
			(end 0.12065 -0.2794)
			(stroke
				(width 0.1)
				(type default)
			)
			(layer "B.Fab")
		)
		(fp_line
			(start 0.67945 -0.305054)
			(end 0.12065 -0.305054)
			(stroke
				(width 0.1)
				(type default)
			)
			(layer "B.Fab")
		)
		(pad "1" smd rect
			(at 0.40005 0 270)
			(size 0.4572 0.508)
			(layers "B.Cu" "B.Mask" "B.Paste")
			(net "P12V_E1S_0_ISENSE_MAM_TIC")
		)
		(pad "2" smd rect
			(at -0.40005 0 270)
			(size 0.4572 0.508)
			(layers "B.Cu" "B.Mask" "B.Paste")
			(net "P12V_E1S_0_ISENSE_TIC")
		)
	)
	(footprint ""
		(layer "B.Cu")
		(at 59.401202 -193.996564)
		(property "Reference" "C136"
			(at 0 0 0)
			(layer "B.SilkS")
			(hide yes)
			(effects
				(font
					(size 1.27 1.27)
				)
				(justify mirror)
			)
		)
		(property "Value" ""
			(at 0 0 0)
			(layer "B.Fab")
			(effects
				(font
					(size 1.27 1.27)
				)
				(justify mirror)
			)
		)
		(duplicate_pad_numbers_are_jumpers no)
		(fp_line
			(start -0.7874 -0.4064)
			(end -0.7874 0.4064)
			(stroke
				(width 0.1524)
				(type default)
			)
			(layer "B.SilkS")
		)
		(fp_line
			(start -0.7874 0.4064)
			(end 0.7874 0.4064)
			(stroke
				(width 0.1524)
				(type default)
			)
			(layer "B.SilkS")
		)
		(fp_line
			(start 0.7874 -0.4064)
			(end -0.7874 -0.4064)
			(stroke
				(width 0.1524)
				(type default)
			)
			(layer "B.SilkS")
		)
		(fp_line
			(start 0.7874 0.4064)
			(end 0.7874 -0.4064)
			(stroke
				(width 0.1524)
				(type default)
			)
			(layer "B.SilkS")
		)
		(fp_line
			(start -0.67945 -0.3048)
			(end -0.67945 0.3048)
			(stroke
				(width 0.1)
				(type default)
			)
			(layer "B.Fab")
		)
		(fp_line
			(start -0.67945 0.3048)
			(end -0.120396 0.3048)
			(stroke
				(width 0.1)
				(type default)
			)
			(layer "B.Fab")
		)
		(fp_line
			(start -0.12065 -0.3048)
			(end -0.67945 -0.3048)
			(stroke
				(width 0.1)
				(type default)
			)
			(layer "B.Fab")
		)
		(fp_line
			(start -0.12065 -0.2794)
			(end -0.12065 -0.3048)
			(stroke
				(width 0.1)
				(type default)
			)
			(layer "B.Fab")
		)
		(fp_line
			(start -0.120396 0.2794)
			(end 0.12065 0.2794)
			(stroke
				(width 0.1)
				(type default)
			)
			(layer "B.Fab")
		)
		(fp_line
			(start -0.120396 0.3048)
			(end -0.120396 0.2794)
			(stroke
				(width 0.1)
				(type default)
			)
			(layer "B.Fab")
		)
		(fp_line
			(start 0.12065 -0.305054)
			(end 0.12065 -0.2794)
			(stroke
				(width 0.1)
				(type default)
			)
			(layer "B.Fab")
		)
		(fp_line
			(start 0.12065 -0.2794)
			(end -0.12065 -0.2794)
			(stroke
				(width 0.1)
				(type default)
			)
			(layer "B.Fab")
		)
		(fp_line
			(start 0.12065 0.2794)
			(end 0.12065 0.3048)
			(stroke
				(width 0.1)
				(type default)
			)
			(layer "B.Fab")
		)
		(fp_line
			(start 0.12065 0.3048)
			(end 0.67945 0.3048)
			(stroke
				(width 0.1)
				(type default)
			)
			(layer "B.Fab")
		)
		(fp_line
			(start 0.67945 -0.305054)
			(end 0.12065 -0.305054)
			(stroke
				(width 0.1)
				(type default)
			)
			(layer "B.Fab")
		)
		(fp_line
			(start 0.67945 0.3048)
			(end 0.67945 -0.305054)
			(stroke
				(width 0.1)
				(type default)
			)
			(layer "B.Fab")
		)
		(pad "1" smd circle
			(at 0.40005 0 180)
			(size 0 0)
			(layers "B.Cu" "B.Mask" "B.Paste")
			(net "P3V3_AUX")
		)
		(pad "2" smd circle
			(at -0.40005 0 180)
			(size 0 0)
			(layers "B.Cu" "B.Mask" "B.Paste")
			(net "GND")
		)
	)
	(footprint ""
		(layer "B.Cu")
		(at 117.102128 -27.441906 180)
		(property "Reference" "C6117"
			(at 0 0 0)
			(layer "B.SilkS")
			(hide yes)
			(effects
				(font
					(size 1.27 1.27)
				)
				(justify mirror)
			)
		)
		(property "Value" ""
			(at 0 0 0)
			(layer "B.Fab")
			(effects
				(font
					(size 1.27 1.27)
				)
				(justify mirror)
			)
		)
		(duplicate_pad_numbers_are_jumpers no)
		(fp_line
			(start 0.7874 0.4064)
			(end 0.7874 -0.4064)
			(stroke
				(width 0.1524)
				(type default)
			)
			(layer "B.SilkS")
		)
		(fp_line
			(start 0.7874 -0.4064)
			(end -0.7874 -0.4064)
			(stroke
				(width 0.1524)
				(type default)
			)
			(layer "B.SilkS")
		)
		(fp_line
			(start -0.7874 0.4064)
			(end 0.7874 0.4064)
			(stroke
				(width 0.1524)
				(type default)
			)
			(layer "B.SilkS")
		)
		(fp_line
			(start -0.7874 -0.4064)
			(end -0.7874 0.4064)
			(stroke
				(width 0.1524)
				(type default)
			)
			(layer "B.SilkS")
		)
		(fp_line
			(start 0.67945 0.3048)
			(end 0.67945 -0.305054)
			(stroke
				(width 0.1)
				(type default)
			)
			(layer "B.Fab")
		)
		(fp_line
			(start 0.67945 -0.305054)
			(end 0.12065 -0.305054)
			(stroke
				(width 0.1)
				(type default)
			)
			(layer "B.Fab")
		)
		(fp_line
			(start 0.12065 0.3048)
			(end 0.67945 0.3048)
			(stroke
				(width 0.1)
				(type default)
			)
			(layer "B.Fab")
		)
		(fp_line
			(start 0.12065 0.2794)
			(end 0.12065 0.3048)
			(stroke
				(width 0.1)
				(type default)
			)
			(layer "B.Fab")
		)
		(fp_line
			(start 0.12065 -0.2794)
			(end -0.12065 -0.2794)
			(stroke
				(width 0.1)
				(type default)
			)
			(layer "B.Fab")
		)
		(fp_line
			(start 0.12065 -0.305054)
			(end 0.12065 -0.2794)
			(stroke
				(width 0.1)
				(type default)
			)
			(layer "B.Fab")
		)
		(fp_line
			(start -0.120396 0.3048)
			(end -0.120396 0.2794)
			(stroke
				(width 0.1)
				(type default)
			)
			(layer "B.Fab")
		)
		(fp_line
			(start -0.120396 0.2794)
			(end 0.12065 0.2794)
			(stroke
				(width 0.1)
				(type default)
			)
			(layer "B.Fab")
		)
		(fp_line
			(start -0.12065 -0.2794)
			(end -0.12065 -0.3048)
			(stroke
				(width 0.1)
				(type default)
			)
			(layer "B.Fab")
		)
		(fp_line
			(start -0.12065 -0.3048)
			(end -0.67945 -0.3048)
			(stroke
				(width 0.1)
				(type default)
			)
			(layer "B.Fab")
		)
		(fp_line
			(start -0.67945 0.3048)
			(end -0.120396 0.3048)
			(stroke
				(width 0.1)
				(type default)
			)
			(layer "B.Fab")
		)
		(fp_line
			(start -0.67945 -0.3048)
			(end -0.67945 0.3048)
			(stroke
				(width 0.1)
				(type default)
			)
			(layer "B.Fab")
		)
		(pad "1" smd circle
			(at 0.40005 0)
			(size 0 0)
			(layers "B.Cu" "B.Mask" "B.Paste")
			(net "P1V2_CPU0_USB2_DVDD12")
		)
		(pad "2" smd circle
			(at -0.40005 0)
			(size 0 0)
			(layers "B.Cu" "B.Mask" "B.Paste")
			(net "GND")
		)
	)
	(footprint ""
		(layer "B.Cu")
		(at 132.630926 -408.517344 90)
		(property "Reference" "C6735"
			(at 0 0 90)
			(layer "B.SilkS")
			(hide yes)
			(effects
				(font
					(size 1.27 1.27)
				)
				(justify mirror)
			)
		)
		(property "Value" ""
			(at 0 0 90)
			(layer "B.Fab")
			(effects
				(font
					(size 1.27 1.27)
				)
				(justify mirror)
			)
		)
		(duplicate_pad_numbers_are_jumpers no)
		(fp_line
			(start 0.299974 -0.150114)
			(end -0.299974 -0.150114)
			(stroke
				(width 0.1)
				(type default)
			)
			(layer "B.Fab")
		)
		(fp_line
			(start -0.299974 -0.150114)
			(end -0.299974 0.150114)
			(stroke
				(width 0.1)
				(type default)
			)
			(layer "B.Fab")
		)
		(fp_line
			(start 0.299974 0.150114)
			(end 0.299974 -0.150114)
			(stroke
				(width 0.1)
				(type default)
			)
			(layer "B.Fab")
		)
		(fp_line
			(start -0.299974 0.150114)
			(end 0.299974 0.150114)
			(stroke
				(width 0.1)
				(type default)
			)
			(layer "B.Fab")
		)
		(pad "1" smd rect
			(at 0.2667 0 270)
			(size 0.3048 0.381)
			(layers "B.Cu" "B.Mask" "B.Paste")
			(net "P5E_CPU1_P3_TX_BUF_C_DP<5>")
		)
		(pad "2" smd rect
			(at -0.2667 0 270)
			(size 0.3048 0.381)
			(layers "B.Cu" "B.Mask" "B.Paste")
			(net "P5E_CPU1_P3_TX_BUF_DP<5>")
		)
	)
	(footprint ""
		(layer "B.Cu")
		(at 382.478534 -395.148562 90)
		(property "Reference" "C1048"
			(at 0 0 90)
			(layer "B.SilkS")
			(hide yes)
			(effects
				(font
					(size 1.27 1.27)
				)
				(justify mirror)
			)
		)
		(property "Value" ""
			(at 0 0 90)
			(layer "B.Fab")
			(effects
				(font
					(size 1.27 1.27)
				)
				(justify mirror)
			)
		)
		(duplicate_pad_numbers_are_jumpers no)
		(fp_line
			(start 0.299974 -0.150114)
			(end -0.299974 -0.150114)
			(stroke
				(width 0.1)
				(type default)
			)
			(layer "B.Fab")
		)
		(fp_line
			(start -0.299974 -0.150114)
			(end -0.299974 0.150114)
			(stroke
				(width 0.1)
				(type default)
			)
			(layer "B.Fab")
		)
		(fp_line
			(start 0.299974 0.150114)
			(end 0.299974 -0.150114)
			(stroke
				(width 0.1)
				(type default)
			)
			(layer "B.Fab")
		)
		(fp_line
			(start -0.299974 0.150114)
			(end 0.299974 0.150114)
			(stroke
				(width 0.1)
				(type default)
			)
			(layer "B.Fab")
		)
		(pad "1" smd rect
			(at 0.2667 0 270)
			(size 0.3048 0.381)
			(layers "B.Cu" "B.Mask" "B.Paste")
			(net "P0V9_CPU0_RT_2D")
		)
		(pad "2" smd rect
			(at -0.2667 0 270)
			(size 0.3048 0.381)
			(layers "B.Cu" "B.Mask" "B.Paste")
			(net "GND")
		)
	)
	(footprint ""
		(layer "B.Cu")
		(at 401.046188 -395.43228)
		(property "Reference" "C781"
			(at 0 0 0)
			(layer "B.SilkS")
			(hide yes)
			(effects
				(font
					(size 1.27 1.27)
				)
				(justify mirror)
			)
		)
		(property "Value" ""
			(at 0 0 0)
			(layer "B.Fab")
			(effects
				(font
					(size 1.27 1.27)
				)
				(justify mirror)
			)
		)
		(duplicate_pad_numbers_are_jumpers no)
		(fp_line
			(start -0.299974 -0.150114)
			(end -0.299974 0.150114)
			(stroke
				(width 0.1)
				(type default)
			)
			(layer "B.Fab")
		)
		(fp_line
			(start -0.299974 0.150114)
			(end 0.299974 0.150114)
			(stroke
				(width 0.1)
				(type default)
			)
			(layer "B.Fab")
		)
		(fp_line
			(start 0.299974 -0.150114)
			(end -0.299974 -0.150114)
			(stroke
				(width 0.1)
				(type default)
			)
			(layer "B.Fab")
		)
		(fp_line
			(start 0.299974 0.150114)
			(end 0.299974 -0.150114)
			(stroke
				(width 0.1)
				(type default)
			)
			(layer "B.Fab")
		)
		(pad "1" smd rect
			(at 0.2667 0 180)
			(size 0.3048 0.381)
			(layers "B.Cu" "B.Mask" "B.Paste")
			(net "P0V9_CPU0_RT2_2A")
		)
		(pad "2" smd rect
			(at -0.2667 0 180)
			(size 0.3048 0.381)
			(layers "B.Cu" "B.Mask" "B.Paste")
			(net "GND")
		)
	)
)
